# S9S_MB_2U (Grand Teton) — schematic netlist excerpt (pin names and nets, part order shuffled) for the footprints in the layout excerpt that follows; sources: Cadence DE-HDL packaged netlist, KiCad conversion of 03242023_DA0F0TMBIJ0_F0T_Motherboard_J_brd_V01_OCP.brd

R2388  Q_RES  0 5% CHIP  pkg 0402LF  page 274 : A = SVID_DIO0_CPU0_R ; B = SVID_DIO_PVCCINFAON_CPU0_R
C2043  Q_CAP  100PF 50V 5% EMPTY  pkg 0402  page 250 : A = P3V3_ADC_MAM ; B = GND

(kicad_pcb
	(version 20260206)
	(generator "pcbnew")
	(generator_version "10.0")
	(general
		(thickness 1.6)
		(legacy_teardrops no)
	)
	(paper "A4")
	(title_block
		(title "03242023_DA0F0TMBIJ0_F0T_Motherboard_J_brd_V01_OCP.brd")
		(comment 1 "Grand Teton / footprints 1182-1183 of 6105")
	)
	(layers
		(0 "F.Cu" signal "TOP")
		(4 "In1.Cu" signal "GND")
		(6 "In2.Cu" signal "IN1")
		(8 "In3.Cu" signal "GND1")
		(10 "In4.Cu" signal "IN2")
		(12 "In5.Cu" signal "GND2")
		(14 "In6.Cu" signal "IN3")
		(16 "In7.Cu" signal "GND3")
		(18 "In8.Cu" signal "VCC")
		(20 "In9.Cu" signal "VCC1")
		(22 "In10.Cu" signal "GND4")
		(24 "In11.Cu" signal "IN4")
		(26 "In12.Cu" signal "GND5")
		(28 "In13.Cu" signal "IN5")
		(30 "In14.Cu" signal "GND6")
		(32 "In15.Cu" signal "IN6")
		(34 "In16.Cu" signal "GND7")
		(2 "B.Cu" signal "BOTTOM")
		(9 "F.Adhes" user "F.Adhesive")
		(11 "B.Adhes" user "B.Adhesive")
		(13 "F.Paste" user "Package Geometry/Pastemask Top")
		(15 "B.Paste" user "Package Geometry/Pastemask Bottom")
		(5 "F.SilkS" user "Ref Des/Silkscreen Top")
		(7 "B.SilkS" user "Ref Des/Silkscreen Bottom")
		(1 "F.Mask" user "Board Geometry/Soldermask Top")
		(3 "B.Mask" user "Board Geometry/Soldermask Bottom")
		(17 "Dwgs.User" user "User.Drawings")
		(19 "Cmts.User" user "User.Comments")
		(21 "Eco1.User" user "User.Eco1")
		(23 "Eco2.User" user "User.Eco2")
		(25 "Edge.Cuts" user "Board Geometry/Outline")
		(27 "Margin" user)
		(31 "F.CrtYd" user "Package Geometry/Place Bound Top")
		(29 "B.CrtYd" user "Package Geometry/Place Bound Bottom")
		(35 "F.Fab" user "Ref Des/Assembly Top")
		(33 "B.Fab" user "Ref Des/Assembly Bottom")
	)
	(footprint ""
		(layer "F.Cu")
		(at 46.350428 -97.808034)
		(property "Reference" "C2043"
			(at 0 0 0)
			(layer "F.SilkS")
			(hide yes)
			(effects
				(font
					(size 1.27 1.27)
				)
			)
		)
		(property "Value" ""
			(at 0 0 0)
			(layer "F.Fab")
			(effects
				(font
					(size 1.27 1.27)
				)
			)
		)
		(duplicate_pad_numbers_are_jumpers no)
		(fp_line
			(start -0.7874 -0.4064)
			(end 0.7874 -0.4064)
			(stroke
				(width 0.1524)
				(type default)
			)
			(layer "F.SilkS")
		)
		(fp_line
			(start -0.7874 0.4064)
			(end -0.7874 -0.4064)
			(stroke
				(width 0.1524)
				(type default)
			)
			(layer "F.SilkS")
		)
		(fp_line
			(start 0.7874 -0.4064)
			(end 0.7874 0.4064)
			(stroke
				(width 0.1524)
				(type default)
			)
			(layer "F.SilkS")
		)
		(fp_line
			(start 0.7874 0.4064)
			(end -0.7874 0.4064)
			(stroke
				(width 0.1524)
				(type default)
			)
			(layer "F.SilkS")
		)
		(fp_line
			(start -0.67945 -0.305054)
			(end -0.12065 -0.305054)
			(stroke
				(width 0.1)
				(type default)
			)
			(layer "F.Fab")
		)
		(fp_line
			(start -0.67945 0.3048)
			(end -0.67945 -0.305054)
			(stroke
				(width 0.1)
				(type default)
			)
			(layer "F.Fab")
		)
		(fp_line
			(start -0.12065 -0.305054)
			(end -0.12065 -0.2794)
			(stroke
				(width 0.1)
				(type default)
			)
			(layer "F.Fab")
		)
		(fp_line
			(start -0.12065 -0.2794)
			(end 0.12065 -0.2794)
			(stroke
				(width 0.1)
				(type default)
			)
			(layer "F.Fab")
		)
		(fp_line
			(start -0.12065 0.2794)
			(end -0.12065 0.3048)
			(stroke
				(width 0.1)
				(type default)
			)
			(layer "F.Fab")
		)
		(fp_line
			(start -0.12065 0.3048)
			(end -0.67945 0.3048)
			(stroke
				(width 0.1)
				(type default)
			)
			(layer "F.Fab")
		)
		(fp_line
			(start 0.120396 0.2794)
			(end -0.12065 0.2794)
			(stroke
				(width 0.1)
				(type default)
			)
			(layer "F.Fab")
		)
		(fp_line
			(start 0.120396 0.3048)
			(end 0.120396 0.2794)
			(stroke
				(width 0.1)
				(type default)
			)
			(layer "F.Fab")
		)
		(fp_line
			(start 0.12065 -0.3048)
			(end 0.67945 -0.3048)
			(stroke
				(width 0.1)
				(type default)
			)
			(layer "F.Fab")
		)
		(fp_line
			(start 0.12065 -0.2794)
			(end 0.12065 -0.3048)
			(stroke
				(width 0.1)
				(type default)
			)
			(layer "F.Fab")
		)
		(fp_line
			(start 0.67945 -0.3048)
			(end 0.67945 0.3048)
			(stroke
				(width 0.1)
				(type default)
			)
			(layer "F.Fab")
		)
		(fp_line
			(start 0.67945 0.3048)
			(end 0.120396 0.3048)
			(stroke
				(width 0.1)
				(type default)
			)
			(layer "F.Fab")
		)
		(pad "1" smd circle
			(at -0.40005 0)
			(size 0 0)
			(layers "F.Cu" "F.Mask" "F.Paste")
			(net "P3V3_ADC_MAM")
		)
		(pad "2" smd circle
			(at 0.40005 0)
			(size 0 0)
			(layers "F.Cu" "F.Mask" "F.Paste")
			(net "GND")
		)
	)
	(footprint ""
		(layer "F.Cu")
		(at 430.600104 -137.542778 180)
		(property "Reference" "R2388"
			(at 0 0 180)
			(layer "F.SilkS")
			(hide yes)
			(effects
				(font
					(size 1.27 1.27)
				)
			)
		)
		(property "Value" ""
			(at 0 0 180)
			(layer "F.Fab")
			(effects
				(font
					(size 1.27 1.27)
				)
			)
		)
		(duplicate_pad_numbers_are_jumpers no)
		(fp_line
			(start 0.7874 0.4064)
			(end -0.7874 0.4064)
			(stroke
				(width 0.1524)
				(type default)
			)
			(layer "F.SilkS")
		)
		(fp_line
			(start 0.7874 -0.4064)
			(end 0.7874 0.4064)
			(stroke
				(width 0.1524)
				(type default)
			)
			(layer "F.SilkS")
		)
		(fp_line
			(start -0.7874 0.4064)
			(end -0.7874 -0.4064)
			(stroke
				(width 0.1524)
				(type default)
			)
			(layer "F.SilkS")
		)
		(fp_line
			(start -0.7874 -0.4064)
			(end 0.7874 -0.4064)
			(stroke
				(width 0.1524)
				(type default)
			)
			(layer "F.SilkS")
		)
		(fp_line
			(start 0.67945 0.3048)
			(end 0.120396 0.3048)
			(stroke
				(width 0.1)
				(type default)
			)
			(layer "F.Fab")
		)
		(fp_line
			(start 0.67945 -0.3048)
			(end 0.67945 0.3048)
			(stroke
				(width 0.1)
				(type default)
			)
			(layer "F.Fab")
		)
		(fp_line
			(start 0.12065 -0.2794)
			(end 0.12065 -0.3048)
			(stroke
				(width 0.1)
				(type default)
			)
			(layer "F.Fab")
		)
		(fp_line
			(start 0.12065 -0.3048)
			(end 0.67945 -0.3048)
			(stroke
				(width 0.1)
				(type default)
			)
			(layer "F.Fab")
		)
		(fp_line
			(start 0.120396 0.3048)
			(end 0.120396 0.2794)
			(stroke
				(width 0.1)
				(type default)
			)
			(layer "F.Fab")
		)
		(fp_line
			(start 0.120396 0.2794)
			(end -0.12065 0.2794)
			(stroke
				(width 0.1)
				(type default)
			)
			(layer "F.Fab")
		)
		(fp_line
			(start -0.12065 0.3048)
			(end -0.67945 0.3048)
			(stroke
				(width 0.1)
				(type default)
			)
			(layer "F.Fab")
		)
		(fp_line
			(start -0.12065 0.2794)
			(end -0.12065 0.3048)
			(stroke
				(width 0.1)
				(type default)
			)
			(layer "F.Fab")
		)
		(fp_line
			(start -0.12065 -0.2794)
			(end 0.12065 -0.2794)
			(stroke
				(width 0.1)
				(type default)
			)
			(layer "F.Fab")
		)
		(fp_line
			(start -0.12065 -0.305054)
			(end -0.12065 -0.2794)
			(stroke
				(width 0.1)
				(type default)
			)
			(layer "F.Fab")
		)
		(fp_line
			(start -0.67945 0.3048)
			(end -0.67945 -0.305054)
			(stroke
				(width 0.1)
				(type default)
			)
			(layer "F.Fab")
		)
		(fp_line
			(start -0.67945 -0.305054)
			(end -0.12065 -0.305054)
			(stroke
				(width 0.1)
				(type default)
			)
			(layer "F.Fab")
		)
		(pad "1" smd circle
			(at -0.40005 0 180)
			(size 0 0)
			(layers "F.Cu" "F.Mask" "F.Paste")
			(net "SVID_DIO0_CPU0_R")
		)
		(pad "2" smd circle
			(at 0.40005 0 180)
			(size 0 0)
			(layers "F.Cu" "F.Mask" "F.Paste")
			(net "SVID_DIO_PVCCINFAON_CPU0_R")
		)
	)
)
